# BASEBOARD_FAB2 (Tioga Pass) — schematic netlist excerpt (pin names and nets, part order shuffled) for the footprints in the layout excerpt that follows; sources: Cadence DE-HDL packaged netlist, KiCad conversion of Wiwynn_Tioga_Pass_MB.brd

C3T4  CAP_A  1.0UF 6.3V 10% X6S  pkg 0402V  page 153 : A = P3V3_STBY ; B = GND
R6W10  RES  4.75K 1% CHIP  pkg 0402  page 247 : A = P3V3_STBY ; B = PCA9555_INT_N
R3N15  RES  1.00K 1% EMPTY  pkg 0402  page 133 : A = P1V05_PCH_STBY ; B = FM_PRSNT_2_4_N

(kicad_pcb
	(version 20260206)
	(generator "pcbnew")
	(generator_version "10.0")
	(general
		(thickness 1.6)
		(legacy_teardrops no)
	)
	(paper "A4")
	(title_block
		(title "Wiwynn_Tioga_Pass_MB.brd")
		(comment 1 "Tioga Pass / footprints 2570-2572 of 4770")
	)
	(layers
		(0 "F.Cu" signal "TOP")
		(4 "In1.Cu" signal "L2GND")
		(6 "In2.Cu" signal "L3")
		(8 "In3.Cu" signal "L4GND")
		(10 "In4.Cu" signal "L5")
		(12 "In5.Cu" signal "L6GND")
		(14 "In6.Cu" signal "L7VCC")
		(16 "In7.Cu" signal "L8VCC")
		(18 "In8.Cu" signal "L9GND")
		(20 "In9.Cu" signal "L10")
		(22 "In10.Cu" signal "L11GND")
		(24 "In11.Cu" signal "L12")
		(26 "In12.Cu" signal "L13GND")
		(2 "B.Cu" signal "BOTTOM")
		(9 "F.Adhes" user "F.Adhesive")
		(11 "B.Adhes" user "B.Adhesive")
		(13 "F.Paste" user "Package Geometry/Pastemask Top")
		(15 "B.Paste" user "Package Geometry/Pastemask Bottom")
		(5 "F.SilkS" user "Ref Des/Silkscreen Top")
		(7 "B.SilkS" user "Ref Des/Silkscreen Bottom")
		(1 "F.Mask" user "Board Geometry/Soldermask Top")
		(3 "B.Mask" user "Board Geometry/Soldermask Bottom")
		(17 "Dwgs.User" user "User.Drawings")
		(19 "Cmts.User" user "User.Comments")
		(21 "Eco1.User" user "User.Eco1")
		(23 "Eco2.User" user "User.Eco2")
		(25 "Edge.Cuts" user "Board Geometry/Outline")
		(27 "Margin" user)
		(31 "F.CrtYd" user "Package Geometry/Place Bound Top")
		(29 "B.CrtYd" user "Package Geometry/Place Bound Bottom")
		(35 "F.Fab" user "Ref Des/Assembly Top")
		(33 "B.Fab" user "Ref Des/Assembly Bottom")
	)
	(footprint ""
		(layer "B.Cu")
		(at 477.698816 -146.359372)
		(property "Reference" "R6W10"
			(at 0.8382 -0.67818 0)
			(unlocked yes)
			(layer "B.SilkS")
			(effects
				(font
					(size 0.4064 0.254)
					(thickness 0.1524)
				)
				(justify left mirror)
			)
		)
		(property "Value" ""
			(at 0 0 0)
			(layer "B.Fab")
			(effects
				(font
					(size 1.27 1.27)
				)
				(justify mirror)
			)
		)
		(duplicate_pad_numbers_are_jumpers no)
		(fp_poly
			(pts
				(xy 0.2794 -0.1016) (xy -0.2794 -0.1016) (xy -0.2794 0.9906) (xy 0.2794 0.9906)
			)
			(stroke
				(width 0)
				(type default)
			)
			(fill no)
			(layer "B.CrtYd")
		)
		(fp_line
			(start -0.2794 -0.1016)
			(end 0.2794 -0.1016)
			(stroke
				(width 0.1)
				(type default)
			)
			(layer "B.Fab")
		)
		(fp_line
			(start -0.2794 0.9906)
			(end -0.2794 -0.1016)
			(stroke
				(width 0.1)
				(type default)
			)
			(layer "B.Fab")
		)
		(fp_line
			(start 0.2794 -0.1016)
			(end 0.2794 0.9906)
			(stroke
				(width 0.1)
				(type default)
			)
			(layer "B.Fab")
		)
		(fp_line
			(start 0.2794 0.9906)
			(end -0.2794 0.9906)
			(stroke
				(width 0.1)
				(type default)
			)
			(layer "B.Fab")
		)
		(pad "1" smd rect
			(at 0 0 180)
			(size 0.508 0.508)
			(layers "B.Cu" "B.Mask" "B.Paste")
			(net "P3V3_STBY")
		)
		(pad "2" smd rect
			(at 0 0.889 180)
			(size 0.508 0.508)
			(layers "B.Cu" "B.Mask" "B.Paste")
			(net "PCA9555_INT_N")
		)
		(zone
			(layer "B.Cu")
			(hatch none 0.5)
			(connect_pads
				(clearance 0)
			)
			(min_thickness 0.25)
			(keepout
				(tracks allowed)
				(vias not_allowed)
				(pads allowed)
				(copperpour not_allowed)
				(footprints allowed)
			)
			(placement
				(enabled no)
				(sheetname "")
			)
			(fill
				(thermal_gap 0.5)
				(thermal_bridge_width 0.5)
				(island_removal_mode 0)
			)
			(polygon
				(pts
					(xy 477.952816 -146.105372) (xy 477.444816 -146.105372) (xy 477.444816 -145.724372) (xy 477.952816 -145.724372)
				)
			)
		)
		(zone
			(layer "B.Cu")
			(hatch none 0.5)
			(connect_pads
				(clearance 0)
			)
			(min_thickness 0.25)
			(keepout
				(tracks not_allowed)
				(vias allowed)
				(pads allowed)
				(copperpour not_allowed)
				(footprints allowed)
			)
			(placement
				(enabled no)
				(sheetname "")
			)
			(fill
				(thermal_gap 0.5)
				(thermal_bridge_width 0.5)
				(island_removal_mode 0)
			)
			(polygon
				(pts
					(xy 477.952816 -145.724372) (xy 477.444816 -145.724372) (xy 477.444816 -146.105372) (xy 477.952816 -146.105372)
				)
			)
		)
	)
	(footprint ""
		(layer "B.Cu")
		(at 371.060472 -93.952822 180)
		(property "Reference" "R3N15"
			(at 0.8382 -0.67818 180)
			(unlocked yes)
			(layer "B.SilkS")
			(effects
				(font
					(size 0.4064 0.254)
					(thickness 0.1524)
				)
				(justify left mirror)
			)
		)
		(property "Value" ""
			(at 0 0 0)
			(layer "B.Fab")
			(effects
				(font
					(size 1.27 1.27)
				)
				(justify mirror)
			)
		)
		(duplicate_pad_numbers_are_jumpers no)
		(fp_poly
			(pts
				(xy 0.2794 -0.1016) (xy -0.2794 -0.1016) (xy -0.2794 0.9906) (xy 0.2794 0.9906)
			)
			(stroke
				(width 0)
				(type default)
			)
			(fill no)
			(layer "B.CrtYd")
		)
		(fp_line
			(start 0.2794 0.9906)
			(end -0.2794 0.9906)
			(stroke
				(width 0.1)
				(type default)
			)
			(layer "B.Fab")
		)
		(fp_line
			(start 0.2794 -0.1016)
			(end 0.2794 0.9906)
			(stroke
				(width 0.1)
				(type default)
			)
			(layer "B.Fab")
		)
		(fp_line
			(start -0.2794 0.9906)
			(end -0.2794 -0.1016)
			(stroke
				(width 0.1)
				(type default)
			)
			(layer "B.Fab")
		)
		(fp_line
			(start -0.2794 -0.1016)
			(end 0.2794 -0.1016)
			(stroke
				(width 0.1)
				(type default)
			)
			(layer "B.Fab")
		)
		(pad "1" smd rect
			(at 0 0)
			(size 0.508 0.508)
			(layers "B.Cu" "B.Mask" "B.Paste")
			(net "P1V05_PCH_STBY")
		)
		(pad "2" smd rect
			(at 0 0.889)
			(size 0.508 0.508)
			(layers "B.Cu" "B.Mask" "B.Paste")
			(net "FM_PRSNT_2_4_N")
		)
		(zone
			(layer "B.Cu")
			(hatch none 0.5)
			(connect_pads
				(clearance 0)
			)
			(min_thickness 0.25)
			(keepout
				(tracks not_allowed)
				(vias allowed)
				(pads allowed)
				(copperpour not_allowed)
				(footprints allowed)
			)
			(placement
				(enabled no)
				(sheetname "")
			)
			(fill
				(thermal_gap 0.5)
				(thermal_bridge_width 0.5)
				(island_removal_mode 0)
			)
			(polygon
				(pts
					(xy 370.806472 -94.587822) (xy 371.314472 -94.587822) (xy 371.314472 -94.206822) (xy 370.806472 -94.206822)
				)
			)
		)
		(zone
			(layer "B.Cu")
			(hatch none 0.5)
			(connect_pads
				(clearance 0)
			)
			(min_thickness 0.25)
			(keepout
				(tracks allowed)
				(vias not_allowed)
				(pads allowed)
				(copperpour not_allowed)
				(footprints allowed)
			)
			(placement
				(enabled no)
				(sheetname "")
			)
			(fill
				(thermal_gap 0.5)
				(thermal_bridge_width 0.5)
				(island_removal_mode 0)
			)
			(polygon
				(pts
					(xy 370.806472 -94.206822) (xy 371.314472 -94.206822) (xy 371.314472 -94.587822) (xy 370.806472 -94.587822)
				)
			)
		)
	)
	(footprint ""
		(layer "B.Cu")
		(at 402.13026 -54.24678)
		(property "Reference" "C3T4"
			(at 0 0 0)
			(layer "B.SilkS")
			(hide yes)
			(effects
				(font
					(size 1.27 1.27)
				)
				(justify mirror)
			)
		)
		(property "Value" ""
			(at 0 0 0)
			(layer "B.Fab")
			(effects
				(font
					(size 1.27 1.27)
				)
				(justify mirror)
			)
		)
		(duplicate_pad_numbers_are_jumpers no)
		(fp_poly
			(pts
				(xy -0.3048 -0.1016) (xy -0.3048 0.9906) (xy 0.3048 0.9906) (xy 0.3048 -0.1016)
			)
			(stroke
				(width 0)
				(type default)
			)
			(fill no)
			(layer "B.CrtYd")
		)
		(fp_line
			(start -0.3048 -0.1016)
			(end 0.3048 -0.1016)
			(stroke
				(width 0.1)
				(type default)
			)
			(layer "B.Fab")
		)
		(fp_line
			(start -0.3048 0.9906)
			(end -0.3048 -0.1016)
			(stroke
				(width 0.1)
				(type default)
			)
			(layer "B.Fab")
		)
		(fp_line
			(start 0.3048 -0.1016)
			(end 0.3048 0.9906)
			(stroke
				(width 0.1)
				(type default)
			)
			(layer "B.Fab")
		)
		(fp_line
			(start 0.3048 0.9906)
			(end -0.3048 0.9906)
			(stroke
				(width 0.1)
				(type default)
			)
			(layer "B.Fab")
		)
		(pad "1" smd rect
			(at 0 0 180)
			(size 0.508 0.508)
			(layers "B.Cu" "B.Mask" "B.Paste")
			(net "P3V3_STBY")
		)
		(pad "2" smd rect
			(at 0 0.889 180)
			(size 0.508 0.508)
			(layers "B.Cu" "B.Mask" "B.Paste")
			(net "GND")
		)
		(zone
			(layer "B.Cu")
			(hatch none 0.5)
			(connect_pads
				(clearance 0)
			)
			(min_thickness 0.25)
			(keepout
				(tracks allowed)
				(vias not_allowed)
				(pads allowed)
				(copperpour not_allowed)
				(footprints allowed)
			)
			(placement
				(enabled no)
				(sheetname "")
			)
			(fill
				(thermal_gap 0.5)
				(thermal_bridge_width 0.5)
				(island_removal_mode 0)
			)
			(polygon
				(pts
					(xy 402.38426 -53.99278) (xy 401.87626 -53.99278) (xy 401.87626 -53.61178) (xy 402.38426 -53.61178)
				)
			)
		)
		(zone
			(layer "B.Cu")
			(hatch none 0.5)
			(connect_pads
				(clearance 0)
			)
			(min_thickness 0.25)
			(keepout
				(tracks not_allowed)
				(vias allowed)
				(pads allowed)
				(copperpour not_allowed)
				(footprints allowed)
			)
			(placement
				(enabled no)
				(sheetname "")
			)
			(fill
				(thermal_gap 0.5)
				(thermal_bridge_width 0.5)
				(island_removal_mode 0)
			)
			(polygon
				(pts
					(xy 402.38426 -53.61178) (xy 401.87626 -53.61178) (xy 401.87626 -53.99278) (xy 402.38426 -53.99278)
				)
			)
		)
	)
)
